(kicad_pcb
	(version 20241229)
	(generator "pcbnew")
	(generator_version "9.0")
	(general
		(thickness 1.6296)
		(legacy_teardrops no)
	)
	(paper "A3")
	(title_block
		(title "Thunderbolt to 10GbE adapter")
		(date "2026-04-21")
		(rev "1.1.0")
		(company "Antmicro Ltd")
		(comment 1 "www.antmicro.com")
		(comment 9 "footprints 123-127 of 703")
	)
	(layers
		(0 "F.Cu" signal)
		(4 "In1.Cu" signal)
		(6 "In2.Cu" signal)
		(8 "In3.Cu" signal)
		(10 "In4.Cu" signal)
		(12 "In5.Cu" signal)
		(14 "In6.Cu" signal)
		(2 "B.Cu" signal)
		(9 "F.Adhes" user "F.Adhesive")
		(11 "B.Adhes" user "B.Adhesive")
		(13 "F.Paste" user)
		(15 "B.Paste" user)
		(5 "F.SilkS" user "F.Silkscreen")
		(7 "B.SilkS" user "B.Silkscreen")
		(1 "F.Mask" user)
		(3 "B.Mask" user)
		(17 "Dwgs.User" user "User.Drawings")
		(19 "Cmts.User" user "User.Comments")
		(21 "Eco1.User" user "User.Eco1")
		(23 "Eco2.User" user "User.Eco2")
		(25 "Edge.Cuts" user)
		(27 "Margin" user)
		(31 "F.CrtYd" user "F.Courtyard")
		(29 "B.CrtYd" user "B.Courtyard")
		(35 "F.Fab" user)
		(33 "B.Fab" user)
	)
	(footprint "antmicro-footprints:LED_0603_1608Metric_G"
		(layer "F.Cu")
		(at 183.2 76)
		(descr "LED SMD 0603 Green")
		(tags "LED SMD 0603 Green")
		(property "Reference" "D10"
			(at -1.2 5.75 0)
			(layer "F.SilkS")
			(effects
				(font
					(size 0.7 0.7)
					(thickness 0.15)
				)
				(justify left bottom)
			)
		)
		(property "Value" "LED_G_0603_LG_L29K-G2J1-24-Z"
			(at -0.001 1.599 0)
			(layer "F.Fab")
			(effects
				(font
					(size 0.7 0.7)
					(thickness 0.15)
				)
				(justify left bottom)
			)
		)
		(property "Datasheet" "https://look.ams-osram.com/m/19ee86b3ae0ee95b/original/LG-L29K.pdf"
			(at 0 0 0)
			(layer "F.Fab")
			(hide yes)
			(effects
				(font
					(size 1.27 1.27)
					(thickness 0.15)
				)
			)
		)
		(property "Description" "LED, Green, SMD, 0603, 20 mA, 1.7 V, 570 nm"
			(at 0 0 0)
			(layer "F.Fab")
			(hide yes)
			(effects
				(font
					(size 1.27 1.27)
					(thickness 0.15)
				)
			)
		)
		(property "MPN" "LG L29K-G2J1-24-Z"
			(at 0 0 0)
			(unlocked yes)
			(layer "F.Fab")
			(hide yes)
			(effects
				(font
					(size 1 1)
					(thickness 0.15)
				)
			)
		)
		(property "Manufacturer" "OSRAM"
			(at 0 0 0)
			(unlocked yes)
			(layer "F.Fab")
			(hide yes)
			(effects
				(font
					(size 1 1)
					(thickness 0.15)
				)
			)
		)
		(property "Color" "Green"
			(at 0 0 0)
			(unlocked yes)
			(layer "F.Fab")
			(hide yes)
			(effects
				(font
					(size 1 1)
					(thickness 0.15)
				)
			)
		)
		(property "Author" "Antmicro"
			(at 0 0 0)
			(unlocked yes)
			(layer "F.Fab")
			(hide yes)
			(effects
				(font
					(size 1 1)
					(thickness 0.15)
				)
			)
		)
		(property "License" "Apache-2.0"
			(at 0 0 0)
			(unlocked yes)
			(layer "F.Fab")
			(hide yes)
			(effects
				(font
					(size 1 1)
					(thickness 0.15)
				)
			)
		)
		(sheetname "/X710 DCDC converters/")
		(sheetfile "DCDC_converters_X710.kicad_sch")
		(attr smd)
		(fp_line
			(start -1.18 -0.319)
			(end -1.18 0.321)
			(stroke
				(width 0.15)
				(type solid)
			)
			(layer "F.SilkS")
		)
		(fp_line
			(start -0.094672 0.001008)
			(end -0.24 0.001008)
			(stroke
				(width 0.1)
				(type solid)
			)
			(layer "F.SilkS")
		)
		(fp_line
			(start -0.094672 0.001008)
			(end 0.105328 -0.198992)
			(stroke
				(width 0.1)
				(type solid)
			)
			(layer "F.SilkS")
		)
		(fp_line
			(start -0.094672 0.201008)
			(end -0.094672 -0.198992)
			(stroke
				(width 0.1)
				(type solid)
			)
			(layer "F.SilkS")
		)
		(fp_line
			(start 0.105328 0.001008)
			(end 0.24 0.001)
			(stroke
				(width 0.1)
				(type solid)
			)
			(layer "F.SilkS")
		)
		(fp_line
			(start 0.105328 0.201008)
			(end -0.094672 0.001008)
			(stroke
				(width 0.1)
				(type solid)
			)
			(layer "F.SilkS")
		)
		(fp_line
			(start 0.105328 0.201008)
			(end 0.105328 -0.198992)
			(stroke
				(width 0.1)
				(type solid)
			)
			(layer "F.SilkS")
		)
		(fp_line
			(start 0.22 -0.35)
			(end -0.22 -0.35)
			(stroke
				(width 0.15)
				(type solid)
			)
			(layer "F.SilkS")
		)
		(fp_line
			(start 0.22 0.35)
			(end -0.22 0.35)
			(stroke
				(width 0.15)
				(type solid)
			)
			(layer "F.SilkS")
		)
		(fp_rect
			(start 1.25 0.65)
			(end -1.25 -0.65)
			(stroke
				(width 0.05)
				(type solid)
			)
			(fill no)
			(layer "F.CrtYd")
		)
		(fp_line
			(start -0.199 -0.202)
			(end -0.199 0.1)
			(stroke
				(width 0.15)
				(type solid)
			)
			(layer "F.Fab")
		)
		(fp_line
			(start -0.199 0)
			(end -0.597 0)
			(stroke
				(width 0.15)
				(type solid)
			)
			(layer "F.Fab")
		)
		(fp_line
			(start -0.199 0.2)
			(end -0.199 0.1)
			(stroke
				(width 0.15)
				(type solid)
			)
			(layer "F.Fab")
		)
		(fp_line
			(start -0.101 0)
			(end 0.201 0.2)
			(stroke
				(width 0.15)
				(type solid)
			)
			(layer "F.Fab")
		)
		(fp_line
			(start 0.201 -0.202)
			(end -0.101 0)
			(stroke
				(width 0.15)
				(type solid)
			)
			(layer "F.Fab")
		)
		(fp_line
			(start 0.201 0)
			(end 0.201 -0.202)
			(stroke
				(width 0.15)
				(type solid)
			)
			(layer "F.Fab")
		)
		(fp_line
			(start 0.201 0.2)
			(end 0.201 0)
			(stroke
				(width 0.15)
				(type solid)
			)
			(layer "F.Fab")
		)
		(fp_line
			(start 0.599 0)
			(end 0.201 0)
			(stroke
				(width 0.15)
				(type solid)
			)
			(layer "F.Fab")
		)
		(fp_rect
			(start 0.848 0.4)
			(end -0.85 -0.402)
			(stroke
				(width 0.15)
				(type solid)
			)
			(fill no)
			(layer "F.Fab")
		)
		(fp_text user "${REFERENCE}"
			(at -1.4224 5.999 0)
			(layer "F.Fab")
			(effects
				(font
					(size 0.7 0.7)
					(thickness 0.15)
				)
				(justify left bottom)
			)
		)
		(fp_text user "License: Apache-2.0"
			(at -1.4224 3.599 0)
			(layer "F.Fab")
			(effects
				(font
					(size 0.7 0.7)
					(thickness 0.15)
				)
				(justify left bottom)
			)
		)
		(fp_text user "Author: Antmicro"
			(at -1.4224 4.799 0)
			(layer "F.Fab")
			(effects
				(font
					(size 0.7 0.7)
					(thickness 0.15)
				)
				(justify left bottom)
			)
		)
		(pad "1" smd roundrect
			(at -0.7 0 180)
			(size 0.8 1)
			(layers "F.Cu" "F.Mask" "F.Paste")
			(roundrect_rratio 0.2)
			(net 417 "Net-(D10-C)")
			(pinfunction "C")
			(pintype "passive")
		)
		(pad "2" smd roundrect
			(at 0.7 0 180)
			(size 0.8 1)
			(layers "F.Cu" "F.Mask" "F.Paste")
			(roundrect_rratio 0.2)
			(net 334 "/X710 DCDC converters/+3V3_OUT")
			(pinfunction "A")
			(pintype "passive")
		)
	)
	(footprint "antmicro-footprints:R_0402_1005Metric"
		(layer "F.Cu")
		(at 143.849998 112.150002)
		(descr "Resistor SMD 0402")
		(tags "resistor SMD 0402")
		(property "Reference" "R107"
			(at 15.349999 17.25 0)
			(layer "F.SilkS")
			(effects
				(font
					(size 0.7 0.7)
					(thickness 0.15)
				)
			)
		)
		(property "Value" "R_30k_0402"
			(at -1.011843 1.772047 0)
			(layer "F.Fab")
			(effects
				(font
					(size 0.7 0.7)
					(thickness 0.15)
				)
				(justify left bottom)
			)
		)
		(property "Datasheet" "https://www.bourns.com/docs/product-datasheets/cr.pdf"
			(at 0 0 0)
			(layer "F.Fab")
			(hide yes)
			(effects
				(font
					(size 1.27 1.27)
					(thickness 0.15)
				)
			)
		)
		(property "Description" "SMD Chip Resistor, 30 kohm, ± 1%, 63 mW, 0402 [1005 Metric], Thick Film, General Purpose"
			(at 0 0 0)
			(layer "F.Fab")
			(hide yes)
			(effects
				(font
					(size 1.27 1.27)
					(thickness 0.15)
				)
			)
		)
		(property "MPN" "CR0402-FX-3002GLF"
			(at 0 0 0)
			(unlocked yes)
			(layer "F.Fab")
			(hide yes)
			(effects
				(font
					(size 1 1)
					(thickness 0.15)
				)
			)
		)
		(property "Manufacturer" "Bourns"
			(at 0 0 0)
			(unlocked yes)
			(layer "F.Fab")
			(hide yes)
			(effects
				(font
					(size 1 1)
					(thickness 0.15)
				)
			)
		)
		(property "License" "Apache-2.0"
			(at 0 0 0)
			(unlocked yes)
			(layer "F.Fab")
			(hide yes)
			(effects
				(font
					(size 1 1)
					(thickness 0.15)
				)
			)
		)
		(property "Author" "Antmicro"
			(at 0 0 0)
			(unlocked yes)
			(layer "F.Fab")
			(hide yes)
			(effects
				(font
					(size 1 1)
					(thickness 0.15)
				)
			)
		)
		(property "Val" "30k"
			(at 0 0 0)
			(unlocked yes)
			(layer "F.Fab")
			(hide yes)
			(effects
				(font
					(size 1 1)
					(thickness 0.15)
				)
			)
		)
		(property "Tolerance" "1%"
			(at 0 0 0)
			(unlocked yes)
			(layer "F.Fab")
			(hide yes)
			(effects
				(font
					(size 1 1)
					(thickness 0.15)
				)
			)
		)
		(sheetname "/X710 DCDC converters/")
		(sheetfile "DCDC_converters_X710.kicad_sch")
		(attr smd)
		(fp_rect
			(start -0.925 -0.47)
			(end 0.925 0.47)
			(stroke
				(width 0.05)
				(type default)
			)
			(fill no)
			(layer "F.CrtYd")
		)
		(fp_rect
			(start -0.5 -0.25)
			(end 0.5 0.25)
			(stroke
				(width 0.15)
				(type solid)
			)
			(fill no)
			(layer "F.Fab")
		)
		(fp_text user "License: Apache-2.0"
			(at -0.95 5.169 0)
			(layer "F.Fab")
			(effects
				(font
					(size 0.7 0.7)
					(thickness 0.15)
				)
				(justify left bottom)
			)
		)
		(fp_text user "${REFERENCE}"
			(at -0.95 3.168 0)
			(layer "F.Fab")
			(effects
				(font
					(size 0.7 0.7)
					(thickness 0.15)
				)
				(justify left bottom)
			)
		)
		(fp_text user "Author: Antmicro"
			(at -0.95 4.169 0)
			(layer "F.Fab")
			(effects
				(font
					(size 0.7 0.7)
					(thickness 0.15)
				)
				(justify left bottom)
			)
		)
		(pad "1" smd roundrect
			(at -0.48 0)
			(size 0.59 0.64)
			(layers "F.Cu" "F.Mask" "F.Paste")
			(roundrect_rratio 0.25)
			(net 23 "GND")
			(pintype "passive")
		)
		(pad "2" smd roundrect
			(at 0.48 0)
			(size 0.59 0.64)
			(layers "F.Cu" "F.Mask" "F.Paste")
			(roundrect_rratio 0.25)
			(net 342 "/X710 DCDC converters/DVDD_FB")
			(pintype "passive")
		)
	)
	(footprint "antmicro-footprints:C_0402_1005Metric"
		(layer "F.Cu")
		(at 132.8 140.4)
		(descr "Capacitor SMD 0402")
		(tags "capacitor SMD 0402")
		(property "Reference" "C28"
			(at 1 0.4 0)
			(layer "F.SilkS")
			(effects
				(font
					(size 0.7 0.7)
					(thickness 0.15)
				)
				(justify left bottom)
			)
		)
		(property "Value" "C_1u_25V_0402"
			(at -1.022927 2.155213 0)
			(layer "F.Fab")
			(effects
				(font
					(size 0.7 0.7)
					(thickness 0.15)
				)
				(justify left bottom)
			)
		)
		(property "Datasheet" "https://www.murata.com/products/productdetail?partno=GRM155R61E105KE11%23"
			(at 0 0 0)
			(layer "F.Fab")
			(hide yes)
			(effects
				(font
					(size 1.27 1.27)
					(thickness 0.15)
				)
			)
		)
		(property "Description" "SMD Multilayer Ceramic Capacitor, 1 µF, 25 V, 0402 [1005 Metric], ± 10%, X5R, GRM Series"
			(at 0 0 0)
			(layer "F.Fab")
			(hide yes)
			(effects
				(font
					(size 1.27 1.27)
					(thickness 0.15)
				)
			)
		)
		(property "MPN" "GRM155R61E105KE11J"
			(at 0 0 0)
			(unlocked yes)
			(layer "F.Fab")
			(hide yes)
			(effects
				(font
					(size 1 1)
					(thickness 0.15)
				)
			)
		)
		(property "Manufacturer" "Murata"
			(at 0 0 0)
			(unlocked yes)
			(layer "F.Fab")
			(hide yes)
			(effects
				(font
					(size 1 1)
					(thickness 0.15)
				)
			)
		)
		(property "License" "Apache-2.0"
			(at 0 0 0)
			(unlocked yes)
			(layer "F.Fab")
			(hide yes)
			(effects
				(font
					(size 1 1)
					(thickness 0.15)
				)
			)
		)
		(property "Author" "Antmicro"
			(at 0 0 0)
			(unlocked yes)
			(layer "F.Fab")
			(hide yes)
			(effects
				(font
					(size 1 1)
					(thickness 0.15)
				)
			)
		)
		(property "Val" "1u"
			(at 0 0 0)
			(unlocked yes)
			(layer "F.Fab")
			(hide yes)
			(effects
				(font
					(size 1 1)
					(thickness 0.15)
				)
			)
		)
		(property "Voltage" "25V"
			(at 0 0 0)
			(unlocked yes)
			(layer "F.Fab")
			(hide yes)
			(effects
				(font
					(size 1 1)
					(thickness 0.15)
				)
			)
		)
		(property "Dielectric" "X5R"
			(at 0 0 0)
			(unlocked yes)
			(layer "F.Fab")
			(hide yes)
			(effects
				(font
					(size 1 1)
					(thickness 0.15)
				)
			)
		)
		(sheetname "/PD and TB DC-DC/")
		(sheetfile "PD_and_TB_DC_DC.kicad_sch")
		(attr smd)
		(fp_rect
			(start -0.925 -0.47)
			(end 0.925 0.47)
			(stroke
				(width 0.05)
				(type default)
			)
			(fill no)
			(layer "F.CrtYd")
		)
		(fp_line
			(start -0.494 -0.25)
			(end 0.504 -0.25)
			(stroke
				(width 0.15)
				(type solid)
			)
			(layer "F.Fab")
		)
		(fp_line
			(start -0.494 0.248)
			(end -0.494 -0.25)
			(stroke
				(width 0.15)
				(type solid)
			)
			(layer "F.Fab")
		)
		(fp_line
			(start 0.504 -0.25)
			(end 0.504 0.248)
			(stroke
				(width 0.15)
				(type solid)
			)
			(layer "F.Fab")
		)
		(fp_line
			(start 0.504 0.248)
			(end -0.494 0.248)
			(stroke
				(width 0.15)
				(type solid)
			)
			(layer "F.Fab")
		)
		(fp_text user "License: Apache-2.0"
			(at -0.939 5.799 0)
			(layer "F.Fab")
			(effects
				(font
					(size 0.7 0.7)
					(thickness 0.15)
				)
				(justify left bottom)
			)
		)
		(fp_text user "Author: Antmicro"
			(at -0.939 3.399 0)
			(layer "F.Fab")
			(effects
				(font
					(size 0.7 0.7)
					(thickness 0.15)
				)
				(justify left bottom)
			)
		)
		(fp_text user "${REFERENCE}"
			(at -0.939 4.599 0)
			(layer "F.Fab")
			(effects
				(font
					(size 0.7 0.7)
					(thickness 0.15)
				)
				(justify left bottom)
			)
		)
		(pad "1" smd roundrect
			(at -0.48 0)
			(size 0.59 0.64)
			(layers "F.Cu" "F.Mask" "F.Paste")
			(roundrect_rratio 0.25)
			(net 23 "GND")
			(pintype "passive")
		)
		(pad "2" smd roundrect
			(at 0.48 0)
			(size 0.59 0.64)
			(layers "F.Cu" "F.Mask" "F.Paste")
			(roundrect_rratio 0.25)
			(net 182 "VBUS")
			(pintype "passive")
		)
	)
	(footprint "antmicro-footprints:MP_Pad6mm_Drill3.2mm"
		(layer "F.Cu")
		(at 120 50)
		(property "Reference" "MP4"
			(at -1.2 -3.4 0)
			(layer "F.SilkS")
			(effects
				(font
					(size 0.7 0.7)
					(thickness 0.15)
				)
				(justify left bottom)
			)
		)
		(property "Value" "MP_Pad6mm_Drill3.2mm"
			(at 0 3.9 0)
			(layer "F.Fab")
			(effects
				(font
					(size 0.7 0.7)
					(thickness 0.15)
				)
				(justify left bottom)
			)
		)
		(property "Description" "Mechanical part"
			(at 0 0 0)
			(layer "F.Fab")
			(hide yes)
			(effects
				(font
					(size 1.27 1.27)
					(thickness 0.15)
				)
			)
		)
		(property "Author" "Antmicro"
			(at 0 0 0)
			(unlocked yes)
			(layer "F.Fab")
			(hide yes)
			(effects
				(font
					(size 1 1)
					(thickness 0.15)
				)
			)
		)
		(property "License" "Apache-2.0"
			(at 0 0 0)
			(unlocked yes)
			(layer "F.Fab")
			(hide yes)
			(effects
				(font
					(size 1 1)
					(thickness 0.15)
				)
			)
		)
		(sheetname "/")
		(sheetfile "thunderbolt-to-10gbe-adapter.kicad_sch")
		(attr exclude_from_pos_files exclude_from_bom)
		(fp_circle
			(center 0 0)
			(end 3.25 0)
			(stroke
				(width 0.05)
				(type default)
			)
			(fill no)
			(layer "F.CrtYd")
		)
		(fp_text user "License: Apache-2.0"
			(at -0.178 8.425 0)
			(layer "F.Fab")
			(effects
				(font
					(size 0.7 0.7)
					(thickness 0.15)
				)
				(justify left bottom)
			)
		)
		(fp_text user "${REFERENCE}"
			(at -0.178 6.025 0)
			(layer "F.Fab")
			(effects
				(font
					(size 0.7 0.7)
					(thickness 0.15)
				)
				(justify left bottom)
			)
		)
		(fp_text user "Author: Antmicro"
			(at -0.178 7.225 0)
			(layer "F.Fab")
			(effects
				(font
					(size 0.7 0.7)
					(thickness 0.15)
				)
				(justify left bottom)
			)
		)
		(pad "1" thru_hole circle
			(at 0 0)
			(size 6 6)
			(drill 3.2)
			(layers "*.Cu" "*.Mask")
			(remove_unused_layers no)
			(net 23 "GND")
			(pintype "passive")
		)
	)
	(footprint "antmicro-footprints:R_0402_1005Metric"
		(layer "F.Cu")
		(at 155.254999 69.074999 90)
		(descr "Resistor SMD 0402")
		(tags "resistor SMD 0402")
		(property "Reference" "R154"
			(at 11.574999 20.295 90)
			(layer "F.SilkS")
			(effects
				(font
					(size 0.7 0.7)
					(thickness 0.15)
				)
			)
		)
		(property "Value" "R_10k_0402"
			(at -1.011843 1.772047 90)
			(layer "F.Fab")
			(effects
				(font
					(size 0.7 0.7)
					(thickness 0.15)
				)
				(justify left bottom)
			)
		)
		(property "Datasheet" "https://www.bourns.com/docs/product-datasheets/cr.pdf"
			(at 0 0 90)
			(layer "F.Fab")
			(hide yes)
			(effects
				(font
					(size 1.27 1.27)
					(thickness 0.15)
				)
			)
		)
		(property "Description" "SMD Chip Resistor, 10 kohm, ± 1%, 62.5 mW, 0402 [1005 Metric], Thick Film, General Purpose"
			(at 0 0 90)
			(layer "F.Fab")
			(hide yes)
			(effects
				(font
					(size 1.27 1.27)
					(thickness 0.15)
				)
			)
		)
		(property "MPN" "CR0402-FX-1002GLF"
			(at 0 0 90)
			(unlocked yes)
			(layer "F.Fab")
			(hide yes)
			(effects
				(font
					(size 1 1)
					(thickness 0.15)
				)
			)
		)
		(property "Manufacturer" "Bourns"
			(at 0 0 90)
			(unlocked yes)
			(layer "F.Fab")
			(hide yes)
			(effects
				(font
					(size 1 1)
					(thickness 0.15)
				)
			)
		)
		(property "License" "Apache-2.0"
			(at 0 0 90)
			(unlocked yes)
			(layer "F.Fab")
			(hide yes)
			(effects
				(font
					(size 1 1)
					(thickness 0.15)
				)
			)
		)
		(property "Author" "Antmicro"
			(at 0 0 90)
			(unlocked yes)
			(layer "F.Fab")
			(hide yes)
			(effects
				(font
					(size 1 1)
					(thickness 0.15)
				)
			)
		)
		(property "Val" "10k"
			(at 0 0 90)
			(unlocked yes)
			(layer "F.Fab")
			(hide yes)
			(effects
				(font
					(size 1 1)
					(thickness 0.15)
				)
			)
		)
		(property "Tolerance" "1%"
			(at 0 0 90)
			(unlocked yes)
			(layer "F.Fab")
			(hide yes)
			(effects
				(font
					(size 1 1)
					(thickness 0.15)
				)
			)
		)
		(sheetname "/X710-AT2 Misc/")
		(sheetfile "x710-at2-mics.kicad_sch")
		(attr smd)
		(fp_rect
			(start -0.925 -0.47)
			(end 0.925 0.47)
			(stroke
				(width 0.05)
				(type default)
			)
			(fill no)
			(layer "F.CrtYd")
		)
		(fp_rect
			(start -0.5 -0.25)
			(end 0.5 0.25)
			(stroke
				(width 0.15)
				(type solid)
			)
			(fill no)
			(layer "F.Fab")
		)
		(fp_text user "License: Apache-2.0"
			(at -0.95 5.169 90)
			(layer "F.Fab")
			(effects
				(font
					(size 0.7 0.7)
					(thickness 0.15)
				)
				(justify left bottom)
			)
		)
		(fp_text user "Author: Antmicro"
			(at -0.95 4.169 90)
			(layer "F.Fab")
			(effects
				(font
					(size 0.7 0.7)
					(thickness 0.15)
				)
				(justify left bottom)
			)
		)
		(fp_text user "${REFERENCE}"
			(at -0.95 3.168 90)
			(layer "F.Fab")
			(effects
				(font
					(size 0.7 0.7)
					(thickness 0.15)
				)
				(justify left bottom)
			)
		)
		(pad "1" smd roundrect
			(at -0.48 0 90)
			(size 0.59 0.64)
			(layers "F.Cu" "F.Mask" "F.Paste")
			(roundrect_rratio 0.25)
			(net 75 "/X710-AT2 Misc/AUX_PWR")
			(pintype "passive")
		)
		(pad "2" smd roundrect
			(at 0.48 0 90)
			(size 0.59 0.64)
			(layers "F.Cu" "F.Mask" "F.Paste")
			(roundrect_rratio 0.25)
			(net 7 "+3V3")
			(pintype "passive")
		)
	)
)
